(kicad_pcb
	(version 20241229)
	(generator "pcbnew")
	(generator_version "9.0")
	(general
		(thickness 1.62)
		(legacy_teardrops no)
	)
	(paper "A3")
	(title_block
		(title "COM Express 7 Baseboard")
		(date "2025-02-04")
		(rev "1.1.2")
		(company "Antmicro Ltd")
		(comment 1 "www.antmicro.com")
		(comment 9 "footprints 571-575 of 802")
	)
	(layers
		(0 "F.Cu" signal)
		(4 "In1.Cu" signal)
		(6 "In2.Cu" signal)
		(8 "In3.Cu" signal)
		(10 "In4.Cu" signal)
		(12 "In5.Cu" signal)
		(14 "In6.Cu" signal)
		(2 "B.Cu" signal)
		(9 "F.Adhes" user "F.Adhesive")
		(11 "B.Adhes" user "B.Adhesive")
		(13 "F.Paste" user)
		(15 "B.Paste" user)
		(5 "F.SilkS" user "F.Silkscreen")
		(7 "B.SilkS" user "B.Silkscreen")
		(1 "F.Mask" user)
		(3 "B.Mask" user)
		(17 "Dwgs.User" user "User.Drawings")
		(19 "Cmts.User" user "User.Comments")
		(21 "Eco1.User" user "User.Eco1")
		(23 "Eco2.User" user "User.Eco2")
		(25 "Edge.Cuts" user)
		(27 "Margin" user)
		(31 "F.CrtYd" user "F.Courtyard")
		(29 "B.CrtYd" user "B.Courtyard")
		(35 "F.Fab" user)
		(33 "B.Fab" user)
	)
	(footprint "antmicro-footprints:R_0402_1005Metric"
		(layer "B.Cu")
		(at 144.25 139.06)
		(descr "Resistor SMD 0402")
		(tags "resistor SMD 0402")
		(property "Reference" "R265"
			(at -1.45 5.4 0)
			(layer "B.SilkS")
			(effects
				(font
					(size 0.7 0.7)
					(thickness 0.15)
				)
				(justify right bottom mirror)
			)
		)
		(property "Value" "R_10k_0402"
			(at -1.011843 -1.772047 0)
			(layer "B.Fab")
			(effects
				(font
					(size 0.7 0.7)
					(thickness 0.15)
				)
				(justify right bottom mirror)
			)
		)
		(property "Datasheet" "https://www.bourns.com/docs/product-datasheets/cr.pdf"
			(at 0 0 0)
			(layer "F.Fab")
			(hide yes)
			(effects
				(font
					(size 1.27 1.27)
					(thickness 0.15)
				)
			)
		)
		(property "Author" "Antmicro"
			(at 0 0 0)
			(layer "B.Fab")
			(hide yes)
			(effects
				(font
					(size 1 1)
					(thickness 0.15)
				)
				(justify mirror)
			)
		)
		(property "License" "Apache-2.0"
			(at 0 0 0)
			(layer "B.Fab")
			(hide yes)
			(effects
				(font
					(size 1 1)
					(thickness 0.15)
				)
				(justify mirror)
			)
		)
		(property "MPN" "CR0402-FX-1002GLF"
			(at 0 0 0)
			(layer "B.Fab")
			(hide yes)
			(effects
				(font
					(size 1 1)
					(thickness 0.15)
				)
				(justify mirror)
			)
		)
		(property "Manufacturer" "Bourns"
			(at 0 0 0)
			(layer "B.Fab")
			(hide yes)
			(effects
				(font
					(size 1 1)
					(thickness 0.15)
				)
				(justify mirror)
			)
		)
		(property "Public" "False"
			(at 0 0 0)
			(layer "B.Fab")
			(hide yes)
			(effects
				(font
					(size 1 1)
					(thickness 0.15)
				)
				(justify mirror)
			)
		)
		(property "Tolerance" "1%"
			(at 0 0 0)
			(layer "B.Fab")
			(hide yes)
			(effects
				(font
					(size 1 1)
					(thickness 0.15)
				)
				(justify mirror)
			)
		)
		(property "Val" "10k"
			(at 0 0 0)
			(layer "B.Fab")
			(hide yes)
			(effects
				(font
					(size 1 1)
					(thickness 0.15)
				)
				(justify mirror)
			)
		)
		(sheetname "KR to SFI #1")
		(sheetfile "kr_sfi.kicad_sch")
		(attr smd)
		(fp_rect
			(start -0.925 0.47)
			(end 0.925 -0.47)
			(stroke
				(width 0.05)
				(type default)
			)
			(fill no)
			(layer "B.CrtYd")
		)
		(fp_rect
			(start -0.5 0.25)
			(end 0.5 -0.25)
			(stroke
				(width 0.15)
				(type solid)
			)
			(fill no)
			(layer "B.Fab")
		)
		(pad "1" smd roundrect
			(at -0.48 0)
			(size 0.59 0.64)
			(layers "B.Cu" "B.Mask" "B.Paste")
			(roundrect_rratio 0.25)
			(net 1 "GND")
			(pintype "passive")
			(teardrops
				(best_length_ratio 0.2)
				(max_length 1)
				(best_width_ratio 0.9)
				(max_width 2)
				(curved_edges yes)
				(filter_ratio 0.9)
				(enabled yes)
				(allow_two_segments yes)
				(prefer_zone_connections yes)
			)
		)
		(pad "2" smd roundrect
			(at 0.48 0)
			(size 0.59 0.64)
			(layers "B.Cu" "B.Mask" "B.Paste")
			(roundrect_rratio 0.25)
			(net 658 "Net-(U43C-PRTAD2)")
			(pintype "passive")
			(teardrops
				(best_length_ratio 0.2)
				(max_length 1)
				(best_width_ratio 0.9)
				(max_width 2)
				(curved_edges yes)
				(filter_ratio 0.9)
				(enabled yes)
				(allow_two_segments yes)
				(prefer_zone_connections yes)
			)
		)
	)
	(footprint "antmicro-footprints:C_0402_1005Metric"
		(layer "B.Cu")
		(at 152.25 160.23 -90)
		(descr "Capacitor SMD 0402")
		(tags "capacitor SMD 0402")
		(property "Reference" "C214"
			(at -1.12 -2.45 90)
			(layer "B.SilkS")
			(effects
				(font
					(size 0.7 0.7)
					(thickness 0.15)
				)
				(justify left bottom mirror)
			)
		)
		(property "Value" "C_100n_0402"
			(at -1.022927 -2.155213 90)
			(layer "B.Fab")
			(effects
				(font
					(size 0.7 0.7)
					(thickness 0.15)
				)
				(justify left bottom mirror)
			)
		)
		(property "Datasheet" "https://www.murata.com/products/productdetail?partno=GRM155R61H104KE14%23"
			(at 0 0 270)
			(layer "F.Fab")
			(hide yes)
			(effects
				(font
					(size 1.27 1.27)
					(thickness 0.15)
				)
			)
		)
		(property "Author" "Antmicro"
			(at -7.98 312.48 0)
			(layer "B.Fab")
			(hide yes)
			(effects
				(font
					(size 1 1)
					(thickness 0.15)
				)
				(justify mirror)
			)
		)
		(property "Dielectric" "X5R"
			(at -7.98 312.48 0)
			(layer "B.Fab")
			(hide yes)
			(effects
				(font
					(size 1 1)
					(thickness 0.15)
				)
				(justify mirror)
			)
		)
		(property "License" "Apache-2.0"
			(at -7.98 312.48 0)
			(layer "B.Fab")
			(hide yes)
			(effects
				(font
					(size 1 1)
					(thickness 0.15)
				)
				(justify mirror)
			)
		)
		(property "MPN" "GRM155R61H104KE14D"
			(at -7.98 312.48 0)
			(layer "B.Fab")
			(hide yes)
			(effects
				(font
					(size 1 1)
					(thickness 0.15)
				)
				(justify mirror)
			)
		)
		(property "Manufacturer" "Murata"
			(at -7.98 312.48 0)
			(layer "B.Fab")
			(hide yes)
			(effects
				(font
					(size 1 1)
					(thickness 0.15)
				)
				(justify mirror)
			)
		)
		(property "Public" "False"
			(at -7.98 312.48 0)
			(layer "B.Fab")
			(hide yes)
			(effects
				(font
					(size 1 1)
					(thickness 0.15)
				)
				(justify mirror)
			)
		)
		(property "Val" "100n"
			(at -7.98 312.48 0)
			(layer "B.Fab")
			(hide yes)
			(effects
				(font
					(size 1 1)
					(thickness 0.15)
				)
				(justify mirror)
			)
		)
		(property "Voltage" "50V"
			(at -7.98 312.48 0)
			(layer "B.Fab")
			(hide yes)
			(effects
				(font
					(size 1 1)
					(thickness 0.15)
				)
				(justify mirror)
			)
		)
		(sheetname "2xSFP+")
		(sheetfile "2xSFP+.kicad_sch")
		(attr smd)
		(fp_rect
			(start -0.925 0.47)
			(end 0.925 -0.47)
			(stroke
				(width 0.05)
				(type default)
			)
			(fill no)
			(layer "B.CrtYd")
		)
		(fp_line
			(start -0.494 0.25)
			(end -0.494 -0.248)
			(stroke
				(width 0.15)
				(type solid)
			)
			(layer "B.Fab")
		)
		(fp_line
			(start 0.504 0.25)
			(end -0.494 0.25)
			(stroke
				(width 0.15)
				(type solid)
			)
			(layer "B.Fab")
		)
		(fp_line
			(start -0.494 -0.248)
			(end 0.504 -0.248)
			(stroke
				(width 0.15)
				(type solid)
			)
			(layer "B.Fab")
		)
		(fp_line
			(start 0.504 -0.248)
			(end 0.504 0.25)
			(stroke
				(width 0.15)
				(type solid)
			)
			(layer "B.Fab")
		)
		(pad "1" smd roundrect
			(at -0.48 0 270)
			(size 0.59 0.64)
			(layers "B.Cu" "B.Mask" "B.Paste")
			(roundrect_rratio 0.25)
			(net 53 "/2xSFP+/SH")
			(pintype "passive")
			(teardrops
				(best_length_ratio 0.2)
				(max_length 1)
				(best_width_ratio 0.9)
				(max_width 2)
				(curved_edges yes)
				(filter_ratio 0.9)
				(enabled yes)
				(allow_two_segments yes)
				(prefer_zone_connections yes)
			)
		)
		(pad "2" smd roundrect
			(at 0.48 0 270)
			(size 0.59 0.64)
			(layers "B.Cu" "B.Mask" "B.Paste")
			(roundrect_rratio 0.25)
			(net 1 "GND")
			(pintype "passive")
			(teardrops
				(best_length_ratio 0.2)
				(max_length 1)
				(best_width_ratio 0.9)
				(max_width 2)
				(curved_edges yes)
				(filter_ratio 0.9)
				(enabled yes)
				(allow_two_segments yes)
				(prefer_zone_connections yes)
			)
		)
	)
	(footprint "antmicro-footprints:C_0402_1005Metric"
		(layer "B.Cu")
		(at 110.35 169.435)
		(descr "Capacitor SMD 0402")
		(tags "capacitor SMD 0402")
		(property "Reference" "C208"
			(at -1.35 -0.525 0)
			(layer "B.SilkS")
			(effects
				(font
					(size 0.7 0.7)
					(thickness 0.15)
				)
				(justify right bottom mirror)
			)
		)
		(property "Value" "C_100n_0402"
			(at -1.022927 -2.155213 0)
			(layer "B.Fab")
			(effects
				(font
					(size 0.7 0.7)
					(thickness 0.15)
				)
				(justify right bottom mirror)
			)
		)
		(property "Datasheet" "https://www.murata.com/products/productdetail?partno=GRM155R61H104KE14%23"
			(at 0 0 0)
			(layer "F.Fab")
			(hide yes)
			(effects
				(font
					(size 1.27 1.27)
					(thickness 0.15)
				)
			)
		)
		(property "Author" "Antmicro"
			(at 0 0 0)
			(layer "B.Fab")
			(hide yes)
			(effects
				(font
					(size 1 1)
					(thickness 0.15)
				)
				(justify mirror)
			)
		)
		(property "Dielectric" "X5R"
			(at 0 0 0)
			(layer "B.Fab")
			(hide yes)
			(effects
				(font
					(size 1 1)
					(thickness 0.15)
				)
				(justify mirror)
			)
		)
		(property "License" "Apache-2.0"
			(at 0 0 0)
			(layer "B.Fab")
			(hide yes)
			(effects
				(font
					(size 1 1)
					(thickness 0.15)
				)
				(justify mirror)
			)
		)
		(property "MPN" "GRM155R61H104KE14D"
			(at 0 0 0)
			(layer "B.Fab")
			(hide yes)
			(effects
				(font
					(size 1 1)
					(thickness 0.15)
				)
				(justify mirror)
			)
		)
		(property "Manufacturer" "Murata"
			(at 0 0 0)
			(layer "B.Fab")
			(hide yes)
			(effects
				(font
					(size 1 1)
					(thickness 0.15)
				)
				(justify mirror)
			)
		)
		(property "Public" "False"
			(at 0 0 0)
			(layer "B.Fab")
			(hide yes)
			(effects
				(font
					(size 1 1)
					(thickness 0.15)
				)
				(justify mirror)
			)
		)
		(property "Val" "100n"
			(at 0 0 0)
			(layer "B.Fab")
			(hide yes)
			(effects
				(font
					(size 1 1)
					(thickness 0.15)
				)
				(justify mirror)
			)
		)
		(property "Voltage" "50V"
			(at 0 0 0)
			(layer "B.Fab")
			(hide yes)
			(effects
				(font
					(size 1 1)
					(thickness 0.15)
				)
				(justify mirror)
			)
		)
		(sheetname "2xSFP+")
		(sheetfile "2xSFP+.kicad_sch")
		(attr smd)
		(fp_rect
			(start -0.925 0.47)
			(end 0.925 -0.47)
			(stroke
				(width 0.05)
				(type default)
			)
			(fill no)
			(layer "B.CrtYd")
		)
		(fp_line
			(start -0.494 -0.248)
			(end 0.504 -0.248)
			(stroke
				(width 0.15)
				(type solid)
			)
			(layer "B.Fab")
		)
		(fp_line
			(start -0.494 0.25)
			(end -0.494 -0.248)
			(stroke
				(width 0.15)
				(type solid)
			)
			(layer "B.Fab")
		)
		(fp_line
			(start 0.504 -0.248)
			(end 0.504 0.25)
			(stroke
				(width 0.15)
				(type solid)
			)
			(layer "B.Fab")
		)
		(fp_line
			(start 0.504 0.25)
			(end -0.494 0.25)
			(stroke
				(width 0.15)
				(type solid)
			)
			(layer "B.Fab")
		)
		(pad "1" smd roundrect
			(at -0.48 0)
			(size 0.59 0.64)
			(layers "B.Cu" "B.Mask" "B.Paste")
			(roundrect_rratio 0.25)
			(net 53 "/2xSFP+/SH")
			(pintype "passive")
			(teardrops
				(best_length_ratio 0.2)
				(max_length 1)
				(best_width_ratio 0.9)
				(max_width 2)
				(curved_edges yes)
				(filter_ratio 0.9)
				(enabled yes)
				(allow_two_segments yes)
				(prefer_zone_connections yes)
			)
		)
		(pad "2" smd roundrect
			(at 0.48 0)
			(size 0.59 0.64)
			(layers "B.Cu" "B.Mask" "B.Paste")
			(roundrect_rratio 0.25)
			(net 1 "GND")
			(pintype "passive")
			(teardrops
				(best_length_ratio 0.2)
				(max_length 1)
				(best_width_ratio 0.9)
				(max_width 2)
				(curved_edges yes)
				(filter_ratio 0.9)
				(enabled yes)
				(allow_two_segments yes)
				(prefer_zone_connections yes)
			)
		)
	)
	(footprint "antmicro-footprints:R_0402_1005Metric"
		(layer "B.Cu")
		(at 99.3 76.81)
		(descr "Resistor SMD 0402")
		(tags "resistor SMD 0402")
		(property "Reference" "R141"
			(at -3.65 0.4 0)
			(layer "B.SilkS")
			(effects
				(font
					(size 0.7 0.7)
					(thickness 0.15)
				)
				(justify right bottom mirror)
			)
		)
		(property "Value" "R_10k_0402"
			(at -1.011843 -1.772047 0)
			(layer "B.Fab")
			(effects
				(font
					(size 0.7 0.7)
					(thickness 0.15)
				)
				(justify right bottom mirror)
			)
		)
		(property "Datasheet" "https://www.bourns.com/docs/product-datasheets/cr.pdf"
			(at 0 0 0)
			(layer "F.Fab")
			(hide yes)
			(effects
				(font
					(size 1.27 1.27)
					(thickness 0.15)
				)
			)
		)
		(property "Description" "SMD Chip Resistor, 10 kohm, ± 1%, 62.5 mW, 0402 [1005 Metric], Thick Film, General Purpose"
			(at 0 0 0)
			(layer "F.Fab")
			(hide yes)
			(effects
				(font
					(size 1.27 1.27)
					(thickness 0.15)
				)
			)
		)
		(property "Author" "Antmicro"
			(at 0 0 0)
			(layer "B.Fab")
			(hide yes)
			(effects
				(font
					(size 1 1)
					(thickness 0.15)
				)
				(justify mirror)
			)
		)
		(property "License" "Apache-2.0"
			(at 0 0 0)
			(layer "B.Fab")
			(hide yes)
			(effects
				(font
					(size 1 1)
					(thickness 0.15)
				)
				(justify mirror)
			)
		)
		(property "MPN" "CR0402-FX-1002GLF"
			(at 0 0 0)
			(layer "B.Fab")
			(hide yes)
			(effects
				(font
					(size 1 1)
					(thickness 0.15)
				)
				(justify mirror)
			)
		)
		(property "Manufacturer" "Bourns"
			(at 0 0 0)
			(layer "B.Fab")
			(hide yes)
			(effects
				(font
					(size 1 1)
					(thickness 0.15)
				)
				(justify mirror)
			)
		)
		(property "Tolerance" "1%"
			(at 0 0 0)
			(layer "B.Fab")
			(hide yes)
			(effects
				(font
					(size 1 1)
					(thickness 0.15)
				)
				(justify mirror)
			)
		)
		(property "Val" "10k"
			(at 0 0 0)
			(layer "B.Fab")
			(hide yes)
			(effects
				(font
					(size 1 1)
					(thickness 0.15)
				)
				(justify mirror)
			)
		)
		(sheetname "Misc")
		(sheetfile "misc.kicad_sch")
		(attr smd)
		(fp_rect
			(start -0.925 0.47)
			(end 0.925 -0.47)
			(stroke
				(width 0.05)
				(type default)
			)
			(fill no)
			(layer "B.CrtYd")
		)
		(fp_rect
			(start -0.5 0.25)
			(end 0.5 -0.25)
			(stroke
				(width 0.15)
				(type solid)
			)
			(fill no)
			(layer "B.Fab")
		)
		(pad "1" smd roundrect
			(at -0.48 0)
			(size 0.59 0.64)
			(layers "B.Cu" "B.Mask" "B.Paste")
			(roundrect_rratio 0.25)
			(net 573 "/GPIO expander/GPIOEX0")
			(pintype "passive")
			(teardrops
				(best_length_ratio 0.2)
				(max_length 1)
				(best_width_ratio 0.9)
				(max_width 2)
				(curved_edges yes)
				(filter_ratio 0.9)
				(enabled yes)
				(allow_two_segments yes)
				(prefer_zone_connections yes)
			)
		)
		(pad "2" smd roundrect
			(at 0.48 0)
			(size 0.59 0.64)
			(layers "B.Cu" "B.Mask" "B.Paste")
			(roundrect_rratio 0.25)
			(net 130 "Net-(D17-C_{G})")
			(pintype "passive")
			(teardrops
				(best_length_ratio 0.2)
				(max_length 1)
				(best_width_ratio 0.9)
				(max_width 2)
				(curved_edges yes)
				(filter_ratio 0.9)
				(enabled yes)
				(allow_two_segments yes)
				(prefer_zone_connections yes)
			)
		)
	)
	(footprint "antmicro-footprints:C_0402_1005Metric"
		(layer "B.Cu")
		(at 128.79 137.86)
		(descr "Capacitor SMD 0402")
		(tags "capacitor SMD 0402")
		(property "Reference" "C187"
			(at -1.39 1.4 0)
			(layer "B.SilkS")
			(effects
				(font
					(size 0.7 0.7)
					(thickness 0.15)
				)
				(justify right bottom mirror)
			)
		)
		(property "Value" "C_100n_0402"
			(at -1.022927 -2.155213 0)
			(layer "B.Fab")
			(effects
				(font
					(size 0.7 0.7)
					(thickness 0.15)
				)
				(justify right bottom mirror)
			)
		)
		(property "Datasheet" "https://www.murata.com/products/productdetail?partno=GRM155R61H104KE14%23"
			(at 0 0 0)
			(layer "F.Fab")
			(hide yes)
			(effects
				(font
					(size 1.27 1.27)
					(thickness 0.15)
				)
			)
		)
		(property "Author" "Antmicro"
			(at 0 0 0)
			(layer "B.Fab")
			(hide yes)
			(effects
				(font
					(size 1 1)
					(thickness 0.15)
				)
				(justify mirror)
			)
		)
		(property "Dielectric" "X5R"
			(at 0 0 0)
			(layer "B.Fab")
			(hide yes)
			(effects
				(font
					(size 1 1)
					(thickness 0.15)
				)
				(justify mirror)
			)
		)
		(property "License" "Apache-2.0"
			(at 0 0 0)
			(layer "B.Fab")
			(hide yes)
			(effects
				(font
					(size 1 1)
					(thickness 0.15)
				)
				(justify mirror)
			)
		)
		(property "MPN" "GRM155R61H104KE14D"
			(at 0 0 0)
			(layer "B.Fab")
			(hide yes)
			(effects
				(font
					(size 1 1)
					(thickness 0.15)
				)
				(justify mirror)
			)
		)
		(property "Manufacturer" "Murata"
			(at 0 0 0)
			(layer "B.Fab")
			(hide yes)
			(effects
				(font
					(size 1 1)
					(thickness 0.15)
				)
				(justify mirror)
			)
		)
		(property "Public" "False"
			(at 0 0 0)
			(layer "B.Fab")
			(hide yes)
			(effects
				(font
					(size 1 1)
					(thickness 0.15)
				)
				(justify mirror)
			)
		)
		(property "Val" "100n"
			(at 0 0 0)
			(layer "B.Fab")
			(hide yes)
			(effects
				(font
					(size 1 1)
					(thickness 0.15)
				)
				(justify mirror)
			)
		)
		(property "Voltage" "50V"
			(at 0 0 0)
			(layer "B.Fab")
			(hide yes)
			(effects
				(font
					(size 1 1)
					(thickness 0.15)
				)
				(justify mirror)
			)
		)
		(sheetname "KR to SFI #2")
		(sheetfile "kr_sfi.kicad_sch")
		(attr smd)
		(fp_rect
			(start -0.925 0.47)
			(end 0.925 -0.47)
			(stroke
				(width 0.05)
				(type default)
			)
			(fill no)
			(layer "B.CrtYd")
		)
		(fp_line
			(start -0.494 -0.248)
			(end 0.504 -0.248)
			(stroke
				(width 0.15)
				(type solid)
			)
			(layer "B.Fab")
		)
		(fp_line
			(start -0.494 0.25)
			(end -0.494 -0.248)
			(stroke
				(width 0.15)
				(type solid)
			)
			(layer "B.Fab")
		)
		(fp_line
			(start 0.504 -0.248)
			(end 0.504 0.25)
			(stroke
				(width 0.15)
				(type solid)
			)
			(layer "B.Fab")
		)
		(fp_line
			(start 0.504 0.25)
			(end -0.494 0.25)
			(stroke
				(width 0.15)
				(type solid)
			)
			(layer "B.Fab")
		)
		(pad "1" smd roundrect
			(at -0.48 0)
			(size 0.59 0.64)
			(layers "B.Cu" "B.Mask" "B.Paste")
			(roundrect_rratio 0.25)
			(net 1 "GND")
			(pintype "passive")
			(teardrops
				(best_length_ratio 0.2)
				(max_length 1)
				(best_width_ratio 0.9)
				(max_width 2)
				(curved_edges yes)
				(filter_ratio 0.9)
				(enabled yes)
				(allow_two_segments yes)
				(prefer_zone_connections yes)
			)
		)
		(pad "2" smd roundrect
			(at 0.48 0)
			(size 0.59 0.64)
			(layers "B.Cu" "B.Mask" "B.Paste")
			(roundrect_rratio 0.25)
			(net 74 "+1V0")
			(pintype "passive")
			(teardrops
				(best_length_ratio 0.2)
				(max_length 1)
				(best_width_ratio 0.9)
				(max_width 2)
				(curved_edges yes)
				(filter_ratio 0.9)
				(enabled yes)
				(allow_two_segments yes)
				(prefer_zone_connections yes)
			)
		)
	)
)
